(kicad_pcb
	(version 20260206)
	(generator "pcbnew")
	(generator_version "10.0")
	(general
		(thickness 1.6)
		(legacy_teardrops no)
	)
	(paper "A4")
	(title_block
		(title "Bryce Canyon_R.DPB_16317-1_OCP.brd")
		(comment 1 "Bryce Canyon / footprints 1000-1006 of 2099")
	)
	(layers
		(0 "F.Cu" signal "TOP")
		(4 "In1.Cu" signal "L2GND")
		(6 "In2.Cu" signal "L3")
		(8 "In3.Cu" signal "L4VCC")
		(10 "In4.Cu" signal "L5VCC")
		(12 "In5.Cu" signal "L6")
		(14 "In6.Cu" signal "L7GND")
		(2 "B.Cu" signal "BOTTOM")
		(9 "F.Adhes" user "F.Adhesive")
		(11 "B.Adhes" user "B.Adhesive")
		(13 "F.Paste" user "Package Geometry/Pastemask Top")
		(15 "B.Paste" user "Package Geometry/Pastemask Bottom")
		(5 "F.SilkS" user "Ref Des/Silkscreen Top")
		(7 "B.SilkS" user "Ref Des/Silkscreen Bottom")
		(1 "F.Mask" user "Board Geometry/Soldermask Top")
		(3 "B.Mask" user "Board Geometry/Soldermask Bottom")
		(17 "Dwgs.User" user "User.Drawings")
		(19 "Cmts.User" user "User.Comments")
		(21 "Eco1.User" user "User.Eco1")
		(23 "Eco2.User" user "User.Eco2")
		(25 "Edge.Cuts" user "Board Geometry/Outline")
		(27 "Margin" user)
		(31 "F.CrtYd" user "Package Geometry/Place Bound Top")
		(29 "B.CrtYd" user "Package Geometry/Place Bound Bottom")
		(35 "F.Fab" user "Ref Des/Assembly Top")
		(33 "B.Fab" user "Ref Des/Assembly Bottom")
	)
	(footprint ""
		(layer "F.Cu")
		(at 161.544 -148.082 -90)
		(property "Reference" "R438"
			(at 0 0 270)
			(layer "F.SilkS")
			(hide yes)
			(effects
				(font
					(size 1.27 1.27)
				)
			)
		)
		(property "Value" "10KR2F-2-GP"
			(at 0.064008 -3.993896 270)
			(unlocked yes)
			(layer "F.Fab")
			(hide yes)
			(effects
				(font
					(size 1.016 1.016)
					(thickness 0.1524)
				)
			)
		)
		(property "Device Type" "R402H16"
			(at 0.064008 -5.517896 270)
			(unlocked yes)
			(layer "F.Fab")
			(hide yes)
			(effects
				(font
					(size 1.016 1.016)
					(thickness 0.1524)
				)
			)
		)
		(duplicate_pad_numbers_are_jumpers no)
		(fp_line
			(start -0.508 -0.9398)
			(end -0.508 0.9398)
			(stroke
				(width 0.1524)
				(type default)
			)
			(layer "F.SilkS")
		)
		(fp_line
			(start 0.508 -0.9398)
			(end -0.508 -0.9398)
			(stroke
				(width 0.1524)
				(type default)
			)
			(layer "F.SilkS")
		)
		(fp_rect
			(start -0.508 0.9398)
			(end 0.508 -0.9398)
			(stroke
				(width 0)
				(type default)
			)
			(fill no)
			(layer "F.CrtYd")
		)
		(fp_rect
			(start -0.508 0.9398)
			(end 0.508 -0.9398)
			(stroke
				(width 0)
				(type default)
			)
			(fill no)
			(layer "F.Fab")
		)
		(pad "1" smd custom
			(at 0 -0.4445 270)
			(size 0.1397 0.1397)
			(layers "F.Cu" "F.Mask" "F.Paste")
			(net "P3V3_STBY_B")
			(options
				(clearance outline)
				(anchor circle)
			)
			(primitives
				(gr_poly
					(pts
						(arc
							(start -0.1778 -0.2794)
							(mid -0.249642 -0.249642)
							(end -0.2794 -0.1778)
						)
						(arc
							(start -0.2794 0.1778)
							(mid -0.249642 0.249642)
							(end -0.1778 0.2794)
						)
						(arc
							(start 0.1778 0.2794)
							(mid 0.249642 0.249642)
							(end 0.2794 0.1778)
						)
						(arc
							(start 0.2794 -0.1778)
							(mid 0.249642 -0.249642)
							(end 0.1778 -0.2794)
						)
					)
					(width 0)
					(fill yes)
				)
			)
		)
		(pad "2" smd custom
			(at 0 0.4445 270)
			(size 0.1397 0.1397)
			(layers "F.Cu" "F.Mask" "F.Paste")
			(net "HDD_PRSNT_16")
			(options
				(clearance outline)
				(anchor circle)
			)
			(primitives
				(gr_poly
					(pts
						(arc
							(start -0.1778 -0.2794)
							(mid -0.249642 -0.249642)
							(end -0.2794 -0.1778)
						)
						(arc
							(start -0.2794 0.1778)
							(mid -0.249642 0.249642)
							(end -0.1778 0.2794)
						)
						(arc
							(start 0.1778 0.2794)
							(mid 0.249642 0.249642)
							(end 0.2794 0.1778)
						)
						(arc
							(start 0.2794 -0.1778)
							(mid 0.249642 -0.249642)
							(end 0.1778 -0.2794)
						)
					)
					(width 0)
					(fill yes)
				)
			)
		)
	)
	(footprint ""
		(layer "F.Cu")
		(at 314.569348 -213.153752)
		(property "Reference" "R300"
			(at 0 0 0)
			(layer "F.SilkS")
			(hide yes)
			(effects
				(font
					(size 1.27 1.27)
				)
			)
		)
		(property "Value" "130R3F-GP"
			(at -0.0254 -2.5146 0)
			(unlocked yes)
			(layer "F.Fab")
			(hide yes)
			(effects
				(font
					(size 1.016 1.016)
					(thickness 0.1524)
				)
			)
		)
		(property "Device Type" "R603H22"
			(at -0.0254 -4.0386 0)
			(unlocked yes)
			(layer "F.Fab")
			(hide yes)
			(effects
				(font
					(size 1.016 1.016)
					(thickness 0.1524)
				)
			)
		)
		(duplicate_pad_numbers_are_jumpers no)
		(fp_line
			(start -0.4826 0)
			(end -0.2032 0)
			(stroke
				(width 0.2032)
				(type default)
			)
			(layer "F.SilkS")
		)
		(fp_line
			(start 0.2032 0)
			(end 0.4826 0)
			(stroke
				(width 0.2032)
				(type default)
			)
			(layer "F.SilkS")
		)
		(fp_rect
			(start -0.5842 1.3335)
			(end 0.5842 -1.3335)
			(stroke
				(width 0)
				(type default)
			)
			(fill no)
			(layer "F.CrtYd")
		)
		(fp_rect
			(start -0.5842 1.3335)
			(end 0.5842 -1.3335)
			(stroke
				(width 0)
				(type default)
			)
			(fill no)
			(layer "F.Fab")
		)
		(pad "1" smd custom
			(at 0 -0.762)
			(size 0.2159 0.2159)
			(layers "F.Cu" "F.Mask" "F.Paste")
			(net "P5V_B_3")
			(options
				(clearance outline)
				(anchor circle)
			)
			(primitives
				(gr_poly
					(pts
						(arc
							(start -0.3302 -0.4318)
							(mid -0.402042 -0.402042)
							(end -0.4318 -0.3302)
						)
						(arc
							(start -0.4318 0.3302)
							(mid -0.402042 0.402042)
							(end -0.3302 0.4318)
						)
						(arc
							(start 0.3302 0.4318)
							(mid 0.402042 0.402042)
							(end 0.4318 0.3302)
						)
						(arc
							(start 0.4318 -0.3302)
							(mid 0.402042 -0.402042)
							(end 0.3302 -0.4318)
						)
					)
					(width 0)
					(fill yes)
				)
			)
		)
		(pad "2" smd custom
			(at 0 0.762)
			(size 0.2159 0.2159)
			(layers "F.Cu" "F.Mask" "F.Paste")
			(net "FLT_HDD6")
			(options
				(clearance outline)
				(anchor circle)
			)
			(primitives
				(gr_poly
					(pts
						(arc
							(start -0.3302 -0.4318)
							(mid -0.402042 -0.402042)
							(end -0.4318 -0.3302)
						)
						(arc
							(start -0.4318 0.3302)
							(mid -0.402042 0.402042)
							(end -0.3302 0.4318)
						)
						(arc
							(start 0.3302 0.4318)
							(mid 0.402042 0.402042)
							(end 0.4318 0.3302)
						)
						(arc
							(start 0.4318 -0.3302)
							(mid 0.402042 -0.402042)
							(end 0.3302 -0.4318)
						)
					)
					(width 0)
					(fill yes)
				)
			)
		)
	)
	(footprint ""
		(layer "F.Cu")
		(at 366.395 -138.938 -90)
		(property "Reference" "Q87"
			(at 0 0 270)
			(layer "F.SilkS")
			(hide yes)
			(effects
				(font
					(size 1.27 1.27)
				)
			)
		)
		(property "Value" "AO4406AL-GP"
			(at -3.707384 -1.5367 270)
			(unlocked yes)
			(layer "F.Fab")
			(hide yes)
			(effects
				(font
					(size 1.016 1.016)
					(thickness 0.1524)
				)
			)
		)
		(property "Device Type" "SOIC8H69"
			(at -3.707384 -3.0607 270)
			(unlocked yes)
			(layer "F.Fab")
			(hide yes)
			(effects
				(font
					(size 1.016 1.016)
					(thickness 0.1524)
				)
			)
		)
		(duplicate_pad_numbers_are_jumpers no)
		(fp_line
			(start -2.6289 3.4417)
			(end -2.6289 1.4732)
			(stroke
				(width 0.381)
				(type default)
			)
			(layer "F.SilkS")
		)
		(fp_line
			(start -2.7432 1.4224)
			(end -2.6416 1.4224)
			(stroke
				(width 0.1524)
				(type default)
			)
			(layer "F.SilkS")
		)
		(fp_line
			(start -2.7432 1.4224)
			(end 2.1336 1.4224)
			(stroke
				(width 0.1524)
				(type default)
			)
			(layer "F.SilkS")
		)
		(fp_line
			(start 2.1336 1.4224)
			(end 2.1336 -1.4224)
			(stroke
				(width 0.1524)
				(type default)
			)
			(layer "F.SilkS")
		)
		(fp_line
			(start -2.1844 -0.0508)
			(end -2.7178 0.508)
			(stroke
				(width 0.1524)
				(type default)
			)
			(layer "F.SilkS")
		)
		(fp_line
			(start -2.7178 -0.508)
			(end -2.1844 -0.0508)
			(stroke
				(width 0.1524)
				(type default)
			)
			(layer "F.SilkS")
		)
		(fp_line
			(start -2.7432 -1.4224)
			(end -2.7432 1.4224)
			(stroke
				(width 0.1524)
				(type default)
			)
			(layer "F.SilkS")
		)
		(fp_line
			(start 2.1336 -1.4224)
			(end -2.7432 -1.4224)
			(stroke
				(width 0.1524)
				(type default)
			)
			(layer "F.SilkS")
		)
		(fp_poly
			(pts
				(xy -2.2098 -1.4224) (xy -2.2098 1.4224) (xy 2.2098 1.4224) (xy 2.2098 -1.4224)
			)
			(stroke
				(width 0)
				(type default)
			)
			(fill yes)
			(layer "F.SilkS")
		)
		(fp_rect
			(start -2.450084 2.999994)
			(end 2.450084 -2.999994)
			(stroke
				(width 0)
				(type default)
			)
			(fill no)
			(layer "F.CrtYd")
		)
		(fp_poly
			(pts
				(xy -2.8194 3.6322) (xy -2.8194 -3.6322) (xy 2.8194 -3.6322) (xy 2.8194 1.18364) (xy 2.450084 1.18364)
				(xy 2.450084 -2.999994) (xy -2.450084 -2.999994) (xy -2.450084 2.999994) (xy 2.450084 2.999994)
				(xy 2.450084 1.18618) (xy 2.8194 1.18618) (xy 2.8194 3.6322)
			)
			(stroke
				(width 0)
				(type default)
			)
			(fill no)
			(layer "F.CrtYd")
		)
		(fp_rect
			(start -2.8194 3.6322)
			(end 2.8194 -3.6322)
			(stroke
				(width 0)
				(type default)
			)
			(fill no)
			(layer "F.Fab")
		)
		(pad "1" smd rect
			(at -1.905 2.54 270)
			(size 0.635 1.651)
			(layers "F.Cu" "F.Mask" "F.Paste")
			(net "P5V_HDD19")
		)
		(pad "2" smd rect
			(at -0.635 2.54 270)
			(size 0.635 1.651)
			(layers "F.Cu" "F.Mask" "F.Paste")
			(net "P5V_HDD19")
		)
		(pad "3" smd rect
			(at 0.635 2.54 270)
			(size 0.635 1.651)
			(layers "F.Cu" "F.Mask" "F.Paste")
			(net "P5V_HDD19")
		)
		(pad "4" smd rect
			(at 1.905 2.54 270)
			(size 0.635 1.651)
			(layers "F.Cu" "F.Mask" "F.Paste")
			(net "SW_HDD_P19")
		)
		(pad "5" smd rect
			(at 1.905 -2.54 270)
			(size 0.635 1.651)
			(layers "F.Cu" "F.Mask" "F.Paste")
			(net "P5V_B_3")
		)
		(pad "6" smd rect
			(at 0.635 -2.54 270)
			(size 0.635 1.651)
			(layers "F.Cu" "F.Mask" "F.Paste")
			(net "P5V_B_3")
		)
		(pad "7" smd rect
			(at -0.635 -2.54 270)
			(size 0.635 1.651)
			(layers "F.Cu" "F.Mask" "F.Paste")
			(net "P5V_B_3")
		)
		(pad "8" smd rect
			(at -1.905 -2.54 270)
			(size 0.635 1.651)
			(layers "F.Cu" "F.Mask" "F.Paste")
			(net "P5V_B_3")
		)
	)
	(footprint ""
		(layer "F.Cu")
		(at 170.815 -375.412)
		(property "Reference" "C539"
			(at 0 0 0)
			(layer "F.SilkS")
			(hide yes)
			(effects
				(font
					(size 1.27 1.27)
				)
			)
		)
		(property "Value" "SC1KP50V2KX-1GP"
			(at 1.1811 -2.7051 0)
			(unlocked yes)
			(layer "F.Fab")
			(hide yes)
			(effects
				(font
					(size 1.016 1.016)
					(thickness 0.1524)
				)
			)
		)
		(property "Device Type" "C402H22"
			(at 1.1811 -4.2291 0)
			(unlocked yes)
			(layer "F.Fab")
			(hide yes)
			(effects
				(font
					(size 1.016 1.016)
					(thickness 0.1524)
				)
			)
		)
		(duplicate_pad_numbers_are_jumpers no)
		(fp_rect
			(start -0.4318 0.9525)
			(end 0.4318 -0.9525)
			(stroke
				(width 0)
				(type default)
			)
			(fill no)
			(layer "F.CrtYd")
		)
		(fp_rect
			(start -0.4318 0.9525)
			(end 0.4318 -0.9525)
			(stroke
				(width 0)
				(type default)
			)
			(fill no)
			(layer "F.Fab")
		)
		(pad "1" smd custom
			(at 0 -0.4445)
			(size 0.1524 0.1524)
			(layers "F.Cu" "F.Mask" "F.Paste")
			(net "MB0_TEMP_B")
			(options
				(clearance outline)
				(anchor circle)
			)
			(primitives
				(gr_poly
					(pts
						(arc
							(start 0.3048 -0.2032)
							(mid 0.275042 -0.275042)
							(end 0.2032 -0.3048)
						)
						(arc
							(start -0.2032 -0.3048)
							(mid -0.275042 -0.275042)
							(end -0.3048 -0.2032)
						)
						(arc
							(start -0.3048 0.2032)
							(mid -0.275042 0.275042)
							(end -0.2032 0.3048)
						)
						(arc
							(start 0.2032 0.3048)
							(mid 0.275042 0.275042)
							(end 0.3048 0.2032)
						)
					)
					(width 0)
					(fill yes)
				)
			)
		)
		(pad "2" smd custom
			(at 0 0.4445)
			(size 0.1524 0.1524)
			(layers "F.Cu" "F.Mask" "F.Paste")
			(net "MB0_TEMP_E")
			(options
				(clearance outline)
				(anchor circle)
			)
			(primitives
				(gr_poly
					(pts
						(arc
							(start 0.3048 -0.2032)
							(mid 0.275042 -0.275042)
							(end 0.2032 -0.3048)
						)
						(arc
							(start -0.2032 -0.3048)
							(mid -0.275042 -0.275042)
							(end -0.3048 -0.2032)
						)
						(arc
							(start -0.3048 0.2032)
							(mid -0.275042 0.275042)
							(end -0.2032 0.3048)
						)
						(arc
							(start 0.2032 0.3048)
							(mid 0.275042 0.275042)
							(end 0.3048 0.2032)
						)
					)
					(width 0)
					(fill yes)
				)
			)
		)
	)
	(footprint ""
		(layer "F.Cu")
		(at 329.819 -160.401 180)
		(property "Reference" "C271"
			(at 0 0 180)
			(layer "F.SilkS")
			(hide yes)
			(effects
				(font
					(size 1.27 1.27)
				)
			)
		)
		(property "Value" "SC1U25V3KX-GP"
			(at 0 -2.8194 180)
			(unlocked yes)
			(layer "F.Fab")
			(hide yes)
			(effects
				(font
					(size 1.016 1.016)
					(thickness 0.1524)
				)
			)
		)
		(property "Device Type" "C603H36"
			(at 0 -4.3434 180)
			(unlocked yes)
			(layer "F.Fab")
			(hide yes)
			(effects
				(font
					(size 1.016 1.016)
					(thickness 0.1524)
				)
			)
		)
		(duplicate_pad_numbers_are_jumpers no)
		(fp_line
			(start 0.508 0)
			(end -0.508 0)
			(stroke
				(width 0.2032)
				(type default)
			)
			(layer "F.SilkS")
		)
		(fp_rect
			(start -0.5842 1.3335)
			(end 0.5842 -1.3335)
			(stroke
				(width 0)
				(type default)
			)
			(fill no)
			(layer "F.CrtYd")
		)
		(fp_rect
			(start -0.5842 1.3335)
			(end 0.5842 -1.3335)
			(stroke
				(width 0)
				(type default)
			)
			(fill no)
			(layer "F.Fab")
		)
		(pad "1" smd custom
			(at 0 -0.762 180)
			(size 0.2159 0.2159)
			(layers "F.Cu" "F.Mask" "F.Paste")
			(net "P12V_HDD18")
			(options
				(clearance outline)
				(anchor circle)
			)
			(primitives
				(gr_poly
					(pts
						(arc
							(start -0.3302 -0.4318)
							(mid -0.402042 -0.402042)
							(end -0.4318 -0.3302)
						)
						(arc
							(start -0.4318 0.3302)
							(mid -0.402042 0.402042)
							(end -0.3302 0.4318)
						)
						(arc
							(start 0.3302 0.4318)
							(mid 0.402042 0.402042)
							(end 0.4318 0.3302)
						)
						(arc
							(start 0.4318 -0.3302)
							(mid 0.402042 -0.402042)
							(end 0.3302 -0.4318)
						)
					)
					(width 0)
					(fill yes)
				)
			)
		)
		(pad "2" smd custom
			(at 0 0.762 180)
			(size 0.2159 0.2159)
			(layers "F.Cu" "F.Mask" "F.Paste")
			(net "GND")
			(options
				(clearance outline)
				(anchor circle)
			)
			(primitives
				(gr_poly
					(pts
						(arc
							(start -0.3302 -0.4318)
							(mid -0.402042 -0.402042)
							(end -0.4318 -0.3302)
						)
						(arc
							(start -0.4318 0.3302)
							(mid -0.402042 0.402042)
							(end -0.3302 0.4318)
						)
						(arc
							(start 0.3302 0.4318)
							(mid 0.402042 0.402042)
							(end 0.4318 0.3302)
						)
						(arc
							(start 0.4318 -0.3302)
							(mid 0.402042 -0.402042)
							(end 0.3302 -0.4318)
						)
					)
					(width 0)
					(fill yes)
				)
			)
		)
	)
	(footprint ""
		(layer "F.Cu")
		(at 436.412386 -119.178578 180)
		(property "Reference" "R1172"
			(at 0 0 180)
			(layer "F.SilkS")
			(hide yes)
			(effects
				(font
					(size 1.27 1.27)
				)
			)
		)
		(property "Value" "619KR2F-GP"
			(at 0.064008 -3.993896 180)
			(unlocked yes)
			(layer "F.Fab")
			(hide yes)
			(effects
				(font
					(size 1.016 1.016)
					(thickness 0.1524)
				)
			)
		)
		(property "Device Type" "R402H16"
			(at 0.064008 -5.517896 180)
			(unlocked yes)
			(layer "F.Fab")
			(hide yes)
			(effects
				(font
					(size 1.016 1.016)
					(thickness 0.1524)
				)
			)
		)
		(duplicate_pad_numbers_are_jumpers no)
		(fp_line
			(start 0.508 -0.9398)
			(end -0.508 -0.9398)
			(stroke
				(width 0.1524)
				(type default)
			)
			(layer "F.SilkS")
		)
		(fp_line
			(start -0.508 -0.9398)
			(end -0.508 0.9398)
			(stroke
				(width 0.1524)
				(type default)
			)
			(layer "F.SilkS")
		)
		(fp_rect
			(start -0.508 0.9398)
			(end 0.508 -0.9398)
			(stroke
				(width 0)
				(type default)
			)
			(fill no)
			(layer "F.CrtYd")
		)
		(fp_rect
			(start -0.508 0.9398)
			(end 0.508 -0.9398)
			(stroke
				(width 0)
				(type default)
			)
			(fill no)
			(layer "F.Fab")
		)
		(pad "1" smd custom
			(at 0 -0.4445 180)
			(size 0.1397 0.1397)
			(layers "F.Cu" "F.Mask" "F.Paste")
			(net "P5V_B_4_RF")
			(options
				(clearance outline)
				(anchor circle)
			)
			(primitives
				(gr_poly
					(pts
						(arc
							(start -0.1778 -0.2794)
							(mid -0.249642 -0.249642)
							(end -0.2794 -0.1778)
						)
						(arc
							(start -0.2794 0.1778)
							(mid -0.249642 0.249642)
							(end -0.1778 0.2794)
						)
						(arc
							(start 0.1778 0.2794)
							(mid 0.249642 0.249642)
							(end 0.2794 0.1778)
						)
						(arc
							(start 0.2794 -0.1778)
							(mid 0.249642 -0.249642)
							(end 0.1778 -0.2794)
						)
					)
					(width 0)
					(fill yes)
				)
			)
		)
		(pad "2" smd custom
			(at 0 0.4445 180)
			(size 0.1397 0.1397)
			(layers "F.Cu" "F.Mask" "F.Paste")
			(net "AGND_P5V_B_4")
			(options
				(clearance outline)
				(anchor circle)
			)
			(primitives
				(gr_poly
					(pts
						(arc
							(start -0.1778 -0.2794)
							(mid -0.249642 -0.249642)
							(end -0.2794 -0.1778)
						)
						(arc
							(start -0.2794 0.1778)
							(mid -0.249642 0.249642)
							(end -0.1778 0.2794)
						)
						(arc
							(start 0.1778 0.2794)
							(mid 0.249642 0.249642)
							(end 0.2794 0.1778)
						)
						(arc
							(start 0.2794 -0.1778)
							(mid 0.249642 -0.249642)
							(end 0.1778 -0.2794)
						)
					)
					(width 0)
					(fill yes)
				)
			)
		)
	)
	(footprint ""
		(layer "F.Cu")
		(at 46.228 -35.687 -90)
		(property "Reference" "C359"
			(at 0 0 270)
			(layer "F.SilkS")
			(hide yes)
			(effects
				(font
					(size 1.27 1.27)
				)
			)
		)
		(property "Value" "SC4D7U25V5KX-1-GP"
			(at -0.0762 -6.1214 270)
			(unlocked yes)
			(layer "F.Fab")
			(hide yes)
			(effects
				(font
					(size 1.016 1.016)
					(thickness 0.1524)
				)
			)
		)
		(property "Device Type" "C805H58"
			(at -0.0762 -8.1534 270)
			(unlocked yes)
			(layer "F.Fab")
			(hide yes)
			(effects
				(font
					(size 1.016 1.016)
					(thickness 0.1524)
				)
			)
		)
		(duplicate_pad_numbers_are_jumpers no)
		(fp_line
			(start 0.635 0)
			(end -0.635 0)
			(stroke
				(width 0.508)
				(type default)
			)
			(layer "F.SilkS")
		)
		(fp_rect
			(start -0.9652 1.778)
			(end 0.9652 -1.778)
			(stroke
				(width 0)
				(type default)
			)
			(fill no)
			(layer "F.CrtYd")
		)
		(fp_poly
			(pts
				(xy -0.9652 -1.778) (xy 0.9652 -1.778) (xy 0.9652 1.778) (xy -0.9652 1.778)
			)
			(stroke
				(width 0)
				(type default)
			)
			(fill no)
			(layer "F.Fab")
		)
		(pad "1" smd rect
			(at 0 -0.9652 270)
			(size 1.397 1.143)
			(layers "F.Cu" "F.Mask" "F.Paste")
			(net "P12V_HDD25")
		)
		(pad "2" smd rect
			(at 0 0.9652 270)
			(size 1.397 1.143)
			(layers "F.Cu" "F.Mask" "F.Paste")
			(net "GND")
		)
	)
)
